FILE_TYPE = CONNECTIVITY;
{Allegro Design Entry HDL 16.6-p007 (v16-6-112F) 10/10/2012}
"PAGE_NUMBER" = 144;
0"NC";
1"GND\g";
2"A_DACRSET";
3"IRQ_PVDDQ_GHJ_VRHOT_LVT3_N";
4"SMB_IPMB_3V3AUX_SCL";
5"SMB_IPMB_3V3AUX_SDA";
6"TP_SMB_STORAGE_BP_3V3AUX_SDA";
7"TP_SMB_STORAGE_BP_3V3AUX_SCL";
8"SMB_IPMB_3V3AUX_SDA_R";
9"PWRGD_SYS_PWROK";
10"TP_DACB";
11"TP_JTAG_BMC_RTCK";
12"TP_DACG";
13"IRQ_HSC_FAULT_N"$PHYS_NET_NAME"IRQ_HSC_FAULT_N"CDS_PHYS_NET_NAME"IRQ_HSC_FAULT_N";
14"FM_BIOS_MRC_DEBUG_MSG_DIS_N"PHYS_NET_NAME"FM_BIOS_MRC_DEBUG_MSG_DIS_N"CDS_PHYS_NET_NAME"FM_BIOS_MRC_DEBUG_MSG_DIS_N";
15"FM_BMC_CPLD_GPO"CDS_PHYS_NET_NAME"FM_BMC_CPLD_GPO"PHYS_NET_NAME"FM_BMC_CPLD_GPO";
16"FM_FLASH_DESC_OVERRIDE_R";
17"FM_CPU_BMC_INIT"CDS_PHYS_NET_NAME"FM_CPU_BMC_INIT";
18"FM_SOL_UART_CH_SEL";
19"IRQ_PVDDQ_DEF_VRHOT_LVT3_N";
20"SGPIO_BMC_CLK_R";
21"SGPIO_BMC_LD_R_N";
22"SGPIO_BMC_DOUT_R";
23"SGPIO_BMC_DIN";
24"FM_CPU_ERR2_LVT3_N";
25"FM_CPU_CATERR_LVT3_N";
26"FM_PCH_BMC_THERMTRIP_N";
27"FM_FAST_PROCHOT_EN_N"CDS_PHYS_NET_NAME"FM_FAST_PROCHOT_EN_N";
28"IRQ_DIMM_SAVE_LVT3_N"CDS_PHYS_NET_NAME"IRQ_DIMM_SAVE_LVT3_N"PHYS_NET_NAME"IRQ_DIMM_SAVE_LVT3_N";
29"JTAG_BMC_TMS";
30"JTAG_BMC_TCK";
31"TP_DACR";
32"SGPIO_BMC_DOUT";
33"SGPIO_BMC_LD_N";
34"SGPIO_BMC_CLK";
35"FM_FLASH_DESC_OVERRIDE";
36"JTAG_BMC_TRST_N";
37"JTAG_BMC_TDI";
38"JTAG_BMC_TDO";
39"SMB_IPMB_3V3AUX_SCL_R";
40"SMB_VR_STBY_LVC3_SCL_R";
41"IRQ_BMC_PCH_SMI_LPC_N";
42"CLK_48M_USB_BMC";
43"FM_CPU0_SKTOCC_LVT3_N";
44"FM_MP_PS_FAIL_N";
45"FM_CPU1_SKTOCC_LVT3_N";
46"PWRGD_PCH_PWROK";
47"SMB_HOST_STBY_LVC3_SCL_R";
48"SMB_HOST_STBY_LVC3_SDA_R";
49"SMB_VR_STBY_LVC3_SDA_R";
50"SMB_SENSOR_BMC_STBY_LVC3_SCL";
51"SMB_SENSOR_BMC_STBY_LVC3_SDA";
52"SMB_SMLINK0_STBY_LVC3_SDA_R";
53"SMB_SMLINK0_STBY_LVC3_SCL_R";
54"SMB_OCP_FRU_STBY_LVC3_SDA_R";
55"SMB_OCP_FRU_STBY_LVC3_SCL_R";
56"SMB_BMC_PMBUS_STBY_LVC3_SCL_R";
57"SMB_BMC_PMBUS_STBY_LVC3_SDA_R";
58"SMB_SLOTX24_STBY_LVC3_SCL_R";
59"SMB_SLOTX24_STBY_LVC3_SDA_R";
60"SMB_OCP_LAN_STBY_LVC3_SCL_R";
61"SMB_OCP_LAN_STBY_LVC3_SDA_R";
%"RES"
"1","(-1500,-2200)","0","mstr_discrete","I57";
;
PACK_TYPE"0402"
ROOM"BMC"
CDS_LIB"mstr_discrete"
CDS_SEC"1"
$SEC"1"
MATERIAL"CHIP"
CDS_LOCATION"R1U14"
VALUE"51"
PART_NUMBER"G21497-048"
LOCATION"R1U14"
WATTAGE"1/16W"
TOLERANCE"5.0%";
"B"
$PN"2"34;
"A"
$PN"1"20;
%"RES"
"1","(-1475,-2050)","0","mstr_discrete","I58";
;
CDS_LOCATION"R1U13"
MATERIAL"CHIP"
CDS_LIB"mstr_discrete"
ROOM"BMC"
PACK_TYPE"0402"
$SEC"1"
CDS_SEC"1"
TOLERANCE"5.0%"
WATTAGE"1/16W"
LOCATION"R1U13"
VALUE"51"
PART_NUMBER"G21497-048";
"B"
$PN"2"32;
"A"
$PN"1"22;
%"RES"
"1","(-1475,-2150)","0","mstr_discrete","I59";
;
MATERIAL"CHIP"
CDS_LOCATION"R1U12"
CDS_LIB"mstr_discrete"
PACK_TYPE"0402"
$SEC"1"
CDS_SEC"1"
ROOM"BMC"
WATTAGE"1/16W"
PART_NUMBER"G21497-048"
TOLERANCE"5.0%"
LOCATION"R1U12"
VALUE"51";
"B"
$PN"2"33;
"A"
$PN"1"21;
%"GND"
"1","(-1600,-3850)","0","mstr_symbols","I72";
;
HDL_POWER"GND"
BODY_TYPE"PLUMBING"
SIZE"1B"
VOLTAGE"0.0V"
CDS_LIB"mstr_symbols";
"A\NAC"1;
%"RES"
"2","(-1600,-3550)","0","mstr_discrete","I73";
;
CDS_LOCATION"R25W58"
CDS_SEC"1"
CDS_LIB"mstr_discrete"
SEC_TYPE"0402"
SEC"1"
ROOM"BMC"
BOM_COST"SM_CONTROLLER"
PART_NUMBER"G21796-344"
PACK_TYPE"0402"
WATTAGE"1/16W"
MATERIAL"CHIP"
TOLERANCE"1%"
VALUE"2.7K"
LOCATION"R25W58";
"A"
$PN"1"2;
"B"
$PN"2"1;
%"RES"
"1","(-1350,-2600)","0","mstr_discrete","I82";
;
CDS_SEC"1"
CDS_LIB"mstr_discrete"
CDS_LOCATION"R1T24"
SEC"1"
SEC_TYPE"0402"
MATERIAL"EMPTY"
WATTAGE"1/16W"
PACK_TYPE"0402"
PART_NUMBER"G21497-005"
TOLERANCE"5%"
LOCATION"R1T24"
VALUE"0.0";
"B"
$PN"2"35;
"A"
$PN"1"16;
%"RES"
"1","(-6725,-3150)","0","mstr_discrete","I89";
;
CDS_SEC"1"
$SEC"1"
CDS_LOCATION"R6W17"
WATTAGE"1/16W"
PART_NUMBER"G21497-005"
ROOM"USB"
BOM_COST"MIO_USB"
CDS_LIB"mstr_discrete"
MATERIAL"CHIP"
TOLERANCE"5%"
LOCATION"R6W17"
PACK_TYPE"0402"
VALUE"0.0";
"B"
$PN"2"39;
"A"
$PN"1"4;
%"RES"
"1","(-6700,-3050)","0","mstr_discrete","I90";
;
CDS_SEC"1"
$SEC"1"
CDS_LOCATION"R6W18"
CDS_LIB"mstr_discrete"
WATTAGE"1/16W"
PART_NUMBER"G21497-005"
ROOM"USB"
BOM_COST"MIO_USB"
MATERIAL"CHIP"
PACK_TYPE"0402"
LOCATION"R6W18"
TOLERANCE"5%"
VALUE"0.0";
"B"
$PN"2"8;
"A"
$PN"1"5;
%"AST2520A1-GP-GP"
"2","(-4375,-2600)","0","w_hdl","I95";
;
CDS_SEC"2"
$SEC"2"
CDS_LOCATION"U25W4"
CDS_LIB"w_hdl"
CDS_LMAN_SYM_OUTLINE"-1150,1150,1150,-1150"
PART_NUMBER"071.2520A.M001"
PACK_TYPE"ASIC2-GB1"
VALUE"AST2520A1-GP-GP"
LOCATION"U25W4";
"GPIOQ5_SDA14"
$PN"N22"61;
"GPIOQ4_SCL14"
$PN"N21"60;
"GPIOB5_LPCPD#_LPCSMI# \B"
$PN"H21"41;
"GPIOK4_SCL7"
$PN"N1"55;
"GPIOK5_SDA7"
$PN"P1"54;
"GPIOK6_SCL8"
$PN"P2"56;
"GPIOK7_SDA8"
$PN"R1"57;
"GPIOA4_TIMER5_SCL9"
$PN"C14"58;
"GPIOA5_TIMER6_SDA9"
$PN"A13"59;
"GPIOI3_SYSMISO"
$PN"C16"16;
"GPIOI2_SYSMOSI"
$PN"B16"15;
"GPIOJ3_SGPMI"
$PN"N4"23;
"GPIOG0_SGPS1CK"
$PN"A19"24;
"GPIOG1_SGPS1LD"
$PN"E19"25;
"GPIOK3_SDA6"
$PN"N2"52;
"GPIOK2_SCL6"
$PN"L1"53;
"GPIOK1_SDA5"
$PN"L4"51;
"GPIOK0_SCL5"
$PN"L3"50;
"GPIOQ3_SDA4"
$PN"B9"48;
"GPIOQ2_SCL4"
$PN"A9"47;
"GPIOQ1_SDA3"
$PN"A10"49;
"GPIOQ0_SCL3"
$PN"A11"40;
"GPIOY7_SDA2"
$PN"P20"6;
"GPIOY6_SCL2"
$PN"M20"7;
"GPIOB7"
$PN"H20"3;
"GPIOB3"
$PN"K18"43;
"GPIOB2"
$PN"L18"44;
"GPIOB1"
$PN"L19"45;
"GPIOB0"
$PN"K19"46;
"TDO"
$PN"D11"38;
"GPIOY5_SDA1"
$PN"M19"8;
"DACB"
$PN"J2"10;
"GPIOG2_SGPS1I0"
$PN"C19"26;
"GPIOG3_SGPS1I1"
$PN"E16"27;
"GPIOJ2_SGPMO"
$PN"N3"22;
"GPIOJ0_SGPMCK"
$PN"R2"20;
"GPIOJ1_SGPMLD"
$PN"L2"21;
"GPIOI6_SPI1MOSI_VBMOSI"
$PN"A14"28;
"GPIOI4_SPI1CS0#_VBCS# \B"
$PN"B15"17;
"GPIOI5_SPI1CK_VBCK"
$PN"C15"18;
"GPIOI0_SYSCS# \B"
$PN"C18"13;
"GPIOI1_SYSCK"
$PN"E15"14;
"NTRST"
$PN"E11"36;
"RTCK"
$PN"C9"11;
"TCK"
$PN"C10"30;
"TDI"
$PN"D12"37;
"TMS"
$PN"C8"29;
"DACG"
$PN"J3"12;
"DACR"
$PN"J4"31;
"DACRSET"
$PN"K4"2;
"GPIOI7_SPI1MISO_VBMISO"
$PN"A15"19;
"GPIOY4_SCL1"
$PN"M18"39;
"GPIOB4_USBCKI"
$PN"J20"42;
"GPIOB6_LPCPME# \B"
$PN"H22"9;
END.
